# S9S_MB_2U (Grand Teton) — schematic netlist excerpt (pin names and nets, part order shuffled) for the footprints in the layout excerpt that follows; sources: Cadence DE-HDL packaged netlist, KiCad conversion of 03242023_DA0F0TMBIJ0_F0T_Motherboard_J_brd_V01_OCP.brd

J30  SCONN288_ADR50017P087CC  SCONN288_ADR50017-P087CC IO  pkg DDR288S_1-1VXB  page 111
  VIN_BULK0  = P12V_S3_AUX_CPU1_NVDIMM
  RFU0  = TP_CHG_CPU1_DIMM2_FRU_0
  VIN_MGMT  = P3V3_AUX
  HSCL  = I3C_SPD_DDREFGH_CPU1_LVC1_SCL_5
  HSDA  = I3C_SPD_DDREFGH_CPU1_LVC1_SDA
  VSS0  = GND
  DQ0_A  = M_G_CPU1_SA_DQ<0>
  VSS1  = GND
  DQ1_A  = M_G_CPU1_SA_DQ<1>
  VSS2  = GND
  DQS0_A_T  = M_G_CPU1_SA_DQS_DP<0>
  DQS0_A_C  = M_G_CPU1_SA_DQS_DN<0>
  VSS3  = GND
  DQ4_A  = M_G_CPU1_SA_DQ<4>
  VSS4  = GND
  DQ5_A  = M_G_CPU1_SA_DQ<5>
  VSS5  = GND
  DQ8_A  = M_G_CPU1_SA_DQ<8>
  VSS6  = GND
  DQ9_A  = M_G_CPU1_SA_DQ<9>
  VSS7  = GND
  DQS1_A_T  = M_G_CPU1_SA_DQS_DP<1>
  DQS1_A_C  = M_G_CPU1_SA_DQS_DN<1>
  VSS8  = GND
  DQ12_A  = M_G_CPU1_SA_DQ<12>
  VSS9  = GND
  DQ13_A  = M_G_CPU1_SA_DQ<13>
  VSS10  = GND
  DQ16_A  = M_G_CPU1_SA_DQ<16>
  VSS11  = GND
  DQ17_A  = M_G_CPU1_SA_DQ<17>
  VSS12  = GND
  DQS2_A_T  = M_G_CPU1_SA_DQS_DP<2>
  DQS2_A_C  = M_G_CPU1_SA_DQS_DN<2>
  VSS13  = GND
  DQ20_A  = M_G_CPU1_SA_DQ<20>
  VSS14  = GND
  DQ21_A  = M_G_CPU1_SA_DQ<21>
  VSS15  = GND
  DQ24_A  = M_G_CPU1_SA_DQ<24>
  VSS16  = GND
  DQ25_A  = M_G_CPU1_SA_DQ<25>
  VSS17  = GND
  DQS3_A_T  = M_G_CPU1_SA_DQS_DP<3>
  DQS3_A_C  = M_G_CPU1_SA_DQS_DN<3>
  VSS18  = GND
  DQ28_A  = M_G_CPU1_SA_DQ<28>
  VSS19  = GND
  DQ29_A  = M_G_CPU1_SA_DQ<29>
  VSS20  = GND
  CB0_A  = M_G_CPU1_SA_CB<0>
  VSS21  = GND
  CB1_A  = M_G_CPU1_SA_CB<1>
  VSS22  = GND
  DQS4_A_T  = M_G_CPU1_SA_DQS_DP<4>
  DQS4_A_C  = M_G_CPU1_SA_DQS_DN<4>
  VSS23  = GND
  CB4_A  = M_G_CPU1_SA_CB<4>
  VSS24  = GND
  CB5_A  = M_G_CPU1_SA_CB<5>
  VSS25  = GND
  ALERT_N  = M_G_CPU1_ALERT_N
  VSS26  = GND
  CS0_A_N  = M_G_CPU1_SA_CS_N<2>
  VSS27  = GND
  CA0_A  = M_G_CPU1_SA_CA<0>
  VSS28  = GND
  CA2_A  = M_G_CPU1_SA_CA<2>
  VSS29  = GND
  CA4_A  = M_G_CPU1_SA_CA<4>
  VSS30  = GND
  CA6_A  = M_G_CPU1_SA_CA<6>
  VSS31  = GND
  PAR_A  = M_G_CPU1_SA_PAR
  VSS32  = GND
  CA0_B  = M_G_CPU1_SB_CA<0>
  VSS33  = GND
  CA2_B  = M_G_CPU1_SB_CA<2>
  VSS34  = GND
  CA4_B  = M_G_CPU1_SB_CA<4>
  VSS35  = GND
  CA6_B  = M_G_CPU1_SB_CA<6>
  VSS36  = GND
  CS0_B_N  = M_G_CPU1_SB_CS_N<2>
  VSS37  = GND
  \lbd||rsp_a_n\  = M_G_CPU1_SA_RSP<1>
  \lbs||rsp_b_n\  = M_G_CPU1_SB_RSP<1>
  VSS38  = GND
  CB4_B  = M_G_CPU1_SB_CB<4>
  VSS39  = GND
  CB5_B  = M_G_CPU1_SB_CB<5>
  VSS40  = GND
  \dqs9_b_t||tdqs9_b_t||dbi4_b_n\  = M_G_CPU1_SB_DQS_DP<9>
  \dqs9_b_c||tdqs9_b_c\  = M_G_CPU1_SB_DQS_DN<9>
  VSS41  = GND
  CB0_B  = M_G_CPU1_SB_CB<0>
  VSS42  = GND
  CB1_B  = M_G_CPU1_SB_CB<1>
  VSS43  = GND
  DQ0_B  = M_G_CPU1_SB_DQ<0>
  VSS44  = GND
  DQ1_B  = M_G_CPU1_SB_DQ<1>
  VSS45  = GND
  DQS0_B_T  = M_G_CPU1_SB_DQS_DP<0>
  DQS0_B_C  = M_G_CPU1_SB_DQS_DN<0>
  VSS46  = GND
  DQ4_B  = M_G_CPU1_SB_DQ<4>
  VSS47  = GND
  DQ5_B  = M_G_CPU1_SB_DQ<5>
  VSS48  = GND
  DQ8_B  = M_G_CPU1_SB_DQ<8>
  VSS49  = GND
  DQ9_B  = M_G_CPU1_SB_DQ<9>
  VSS50  = GND
  DQS1_B_T  = M_G_CPU1_SB_DQS_DP<1>
  DQS1_B_C  = M_G_CPU1_SB_DQS_DN<1>
  VSS51  = GND
  DQ12_B  = M_G_CPU1_SB_DQ<12>
  VSS52  = GND
  DQ13_B  = M_G_CPU1_SB_DQ<13>
  VSS53  = GND
  DQ16_B  = M_G_CPU1_SB_DQ<16>
  VSS54  = GND
  DQ17_B  = M_G_CPU1_SB_DQ<17>
  VSS55  = GND
  DQS2_B_T  = M_G_CPU1_SB_DQS_DP<2>
  DQS2_B_C  = M_G_CPU1_SB_DQS_DN<2>
  VSS56  = GND
  DQ20_B  = M_G_CPU1_SB_DQ<20>
  VSS57  = GND
  DQ21_B  = M_G_CPU1_SB_DQ<21>
  VSS58  = GND
  DQ24_B  = M_G_CPU1_SB_DQ<24>
  VSS59  = GND
  DQ25_B  = M_G_CPU1_SB_DQ<25>
  VSS60  = GND
  DQS3_B_T  = M_G_CPU1_SB_DQS_DP<3>
  DQS3_B_C  = M_G_CPU1_SB_DQS_DN<3>
  VSS61  = GND
  DQ28_B  = M_G_CPU1_SB_DQ<28>
  VSS62  = GND
  DQ29_B  = M_G_CPU1_SB_DQ<29>
  VSS63  = GND
  RFU1  = TP_CHG_CPU1_DIMM2_FRU_1
  VIN_BULK1  = P12V_S3_AUX_CPU1_NVDIMM
  VIN_BULK2  = P12V_S3_AUX_CPU1_NVDIMM
  \pwr_good||fail_n\  = PWRGD_CHG_CPU1_DIMM2
  HSA  = PD_CHG_CPU1_DIMM2_SAA
  RFU2  = TP_CHG_CPU1_DIMM2_FRU_2
  RFU3  = TP_CHG_CPU1_DIMM2_FRU_3
  VSS64  = GND
  DQ2_A  = M_G_CPU1_SA_DQ<2>
  VSS65  = GND
  DQ3_A  = M_G_CPU1_SA_DQ<3>
  VSS66  = GND
  \dqs5_a_c||tdqs5_a_c||dqs5_a_t||tdqs5_a_t\  = M_G_CPU1_SA_DQS_DN<5>
  \dqs5_a_t||tdqs5_a_t\  = M_G_CPU1_SA_DQS_DP<5>
  VSS67  = GND
  DQ6_A  = M_G_CPU1_SA_DQ<6>
  VSS68  = GND
  DQ7_A  = M_G_CPU1_SA_DQ<7>
  VSS69  = GND
  DQ10_A  = M_G_CPU1_SA_DQ<10>
  VSS70  = GND
  DQ11_A  = M_G_CPU1_SA_DQ<11>
  VSS71  = GND
  \dqs6_a_c||tdqs6_a_c||dqs6_a_t||tdqs6_a_t\  = M_G_CPU1_SA_DQS_DN<6>
  \dqs6_a_t||tdqs6_a_t\  = M_G_CPU1_SA_DQS_DP<6>
  VSS72  = GND
  DQ14_A  = M_G_CPU1_SA_DQ<14>
  VSS73  = GND
  DQ15_A  = M_G_CPU1_SA_DQ<15>
  VSS74  = GND
  DQ18_A  = M_G_CPU1_SA_DQ<18>
  VSS75  = GND
  DQ19_A  = M_G_CPU1_SA_DQ<19>
  VSS76  = GND
  \dqs7_a_c||tdqs7_a_c\  = M_G_CPU1_SA_DQS_DN<7>
  \dqs7_a_t||tdqs7_a_t\  = M_G_CPU1_SA_DQS_DP<7>
  VSS77  = GND
  DQ22_A  = M_G_CPU1_SA_DQ<22>
  VSS78  = GND
  DQ23_A  = M_G_CPU1_SA_DQ<23>
  VSS79  = GND
  DQ26_A  = M_G_CPU1_SA_DQ<26>
  VSS80  = GND
  DQ27_A  = M_G_CPU1_SA_DQ<27>
  VSS81  = GND
  \dqs8_a_c||tdqs8_a_c\  = M_G_CPU1_SA_DQS_DN<8>
  \dqs8_a_t||tdqs8_a_t\  = M_G_CPU1_SA_DQS_DP<8>
  VSS82  = GND
  DQ30_A  = M_G_CPU1_SA_DQ<30>
  VSS83  = GND
  DQ31_A  = M_G_CPU1_SA_DQ<31>
  VSS84  = GND
  CB2_A  = M_G_CPU1_SA_CB<2>
  VSS85  = GND
  CB3_A  = M_G_CPU1_SA_CB<3>
  VSS86  = GND
  \dqs9_a_c||tdqs9_a_c\  = M_G_CPU1_SA_DQS_DN<9>
  \dqs9_a_t||tdqs9_a_t\  = M_G_CPU1_SA_DQS_DP<9>
  VSS87  = GND
  CB6_A  = M_G_CPU1_SA_CB<6>
  VSS88  = GND
  CB7_A  = M_G_CPU1_SA_CB<7>
  VSS89  = GND
  RESET_N  = RST_M_GH_CPU1_FPGA_N
  VSS90  = GND
  CS1_A_N  = M_G_CPU1_SA_CS_N<3>
  VSS91  = GND
  CA1_A  = M_G_CPU1_SA_CA<1>
  VSS92  = GND
  CA3_A  = M_G_CPU1_SA_CA<3>
  VSS93  = GND
  CA5_A  = M_G_CPU1_SA_CA<5>
  VSS94  = GND
  CK_T  = M_G_CPU1_CLK_DP<1>
  CK_C  = M_G_CPU1_CLK_DN<1>
  VSS95  = GND
  RFU4  = TP_CHG_CPU1_DIMM2_FRU_4
  CA1_B  = M_G_CPU1_SB_CA<1>
  VSS96  = GND
  CA3_B  = M_G_CPU1_SB_CA<3>
  VSS97  = GND
  CA5_B  = M_G_CPU1_SB_CA<5>
  VSS98  = GND
  PAR_B  = M_G_CPU1_SB_PAR
  VSS99  = GND
  CS1_B_N  = M_G_CPU1_SB_CS_N<3>
  VSS100  = GND
  RFU5  = TP_CHG_CPU1_DIMM2_FRU_5
  RFU6  = TP_CHG_CPU1_DIMM2_FRU_6
  VSS101  = GND
  CB6_B  = M_G_CPU1_SB_CB<6>
  VSS102  = GND
  CB7_B  = M_G_CPU1_SB_CB<7>
  VSS103  = GND
  DQS4_B_C  = M_G_CPU1_SB_DQS_DN<4>
  DQS4_B_T  = M_G_CPU1_SB_DQS_DP<4>
  VSS104  = GND
  CB2_B  = M_G_CPU1_SB_CB<2>
  VSS105  = GND
  CB3_B  = M_G_CPU1_SB_CB<3>
  VSS106  = GND
  DQ2_B  = M_G_CPU1_SB_DQ<2>
  VSS107  = GND
  DQ3_B  = M_G_CPU1_SB_DQ<3>
  VSS108  = GND
  \dqs5_b_c||tdqs5_b_c\  = M_G_CPU1_SB_DQS_DN<5>
  \dqs5_b_t||tdqs5_b_t\  = M_G_CPU1_SB_DQS_DP<5>
  VSS109  = GND
  DQ6_B  = M_G_CPU1_SB_DQ<6>
  VSS110  = GND
  DQ7_B  = M_G_CPU1_SB_DQ<7>
  VSS111  = GND
  DQ10_B  = M_G_CPU1_SB_DQ<10>
  VSS112  = GND
  DQ11_B  = M_G_CPU1_SB_DQ<11>
  VSS113  = GND
  \dqs6_b_c||tdqs6_b_c\  = M_G_CPU1_SB_DQS_DN<6>
  \dqs6_b_t||tdqs6_b_t\  = M_G_CPU1_SB_DQS_DP<6>
  VSS114  = GND
  DQ14_B  = M_G_CPU1_SB_DQ<14>
  VSS115  = GND
  DQ15_B  = M_G_CPU1_SB_DQ<15>
  VSS116  = GND
  DQ18_B  = M_G_CPU1_SB_DQ<18>
  VSS117  = GND
  DQ19_B  = M_G_CPU1_SB_DQ<19>
  VSS118  = GND
  \dqs7_b_c||tdqs7_b_c\  = M_G_CPU1_SB_DQS_DN<7>
  \dqs7_b_t||tdqs7_b_t\  = M_G_CPU1_SB_DQS_DP<7>
  VSS119  = GND
  DQ22_B  = M_G_CPU1_SB_DQ<22>
  VSS120  = GND
  DQ23_B  = M_G_CPU1_SB_DQ<23>
  VSS121  = GND
  DQ26_B  = M_G_CPU1_SB_DQ<26>
  VSS122  = GND
  DQ27_B  = M_G_CPU1_SB_DQ<27>
  VSS123  = GND
  \dqs8_b_c||tdqs8_b_c\  = M_G_CPU1_SB_DQS_DN<8>
  \dqs8_b_t||tdqs8_b_t\  = M_G_CPU1_SB_DQS_DP<8>
  VSS124  = GND
  DQ30_B  = M_G_CPU1_SB_DQ<30>
  VSS125  = GND
  DQ31_B  = M_G_CPU1_SB_DQ<31>
  VSS126  = GND
  G1  = GND
  G2  = GND
  G3  = GND

(kicad_pcb
	(version 20260206)
	(generator "pcbnew")
	(generator_version "10.0")
	(general
		(thickness 1.6)
		(legacy_teardrops no)
	)
	(paper "A4")
	(title_block
		(title "03242023_DA0F0TMBIJ0_F0T_Motherboard_J_brd_V01_OCP.brd")
		(comment 1 "Grand Teton / footprint 1354 of 6105 (J30), pads 92-137 of 291")
	)
	(layers
		(0 "F.Cu" signal "TOP")
		(4 "In1.Cu" signal "GND")
		(6 "In2.Cu" signal "IN1")
		(8 "In3.Cu" signal "GND1")
		(10 "In4.Cu" signal "IN2")
		(12 "In5.Cu" signal "GND2")
		(14 "In6.Cu" signal "IN3")
		(16 "In7.Cu" signal "GND3")
		(18 "In8.Cu" signal "VCC")
		(20 "In9.Cu" signal "VCC1")
		(22 "In10.Cu" signal "GND4")
		(24 "In11.Cu" signal "IN4")
		(26 "In12.Cu" signal "GND5")
		(28 "In13.Cu" signal "IN5")
		(30 "In14.Cu" signal "GND6")
		(32 "In15.Cu" signal "IN6")
		(34 "In16.Cu" signal "GND7")
		(2 "B.Cu" signal "BOTTOM")
		(9 "F.Adhes" user "F.Adhesive")
		(11 "B.Adhes" user "B.Adhesive")
		(13 "F.Paste" user "Package Geometry/Pastemask Top")
		(15 "B.Paste" user "Package Geometry/Pastemask Bottom")
		(5 "F.SilkS" user "Ref Des/Silkscreen Top")
		(7 "B.SilkS" user "Ref Des/Silkscreen Bottom")
		(1 "F.Mask" user "Board Geometry/Soldermask Top")
		(3 "B.Mask" user "Board Geometry/Soldermask Bottom")
		(17 "Dwgs.User" user "User.Drawings")
		(19 "Cmts.User" user "User.Comments")
		(21 "Eco1.User" user "User.Eco1")
		(23 "Eco2.User" user "User.Eco2")
		(25 "Edge.Cuts" user "Board Geometry/Outline")
		(27 "Margin" user)
		(31 "F.CrtYd" user "Package Geometry/Place Bound Top")
		(29 "B.CrtYd" user "Package Geometry/Place Bound Bottom")
		(35 "F.Fab" user "Ref Des/Assembly Top")
		(33 "B.Fab" user "Ref Des/Assembly Bottom")
	)
	(footprint ""
		(layer "F.Cu")
		(at 191.03848 -258.091686)
		(property "Reference" "J30"
			(at -2.98196 -81.740248 0)
			(unlocked yes)
			(layer "F.SilkS")
			(effects
				(font
					(size 0.7874 0.5842)
					(thickness 0.1524)
				)
				(justify left)
			)
		)
		(property "Value" ""
			(at 0 0 0)
			(layer "F.Fab")
			(effects
				(font
					(size 1.27 1.27)
				)
			)
		)
		(duplicate_pad_numbers_are_jumpers no)
		(pad "92" smd rect
			(at -2.050034 19.12493 270)
			(size 0.519938 1.4986)
			(layers "F.Cu" "F.Mask" "F.Paste")
			(net "GND")
		)
		(pad "93" smd rect
			(at -2.050034 19.975068 270)
			(size 0.519938 1.4986)
			(layers "F.Cu" "F.Mask" "F.Paste")
			(net "M_G_CPU1_SB_DQS_DP<9>")
		)
		(pad "94" smd rect
			(at -2.050034 20.824952 270)
			(size 0.519938 1.4986)
			(layers "F.Cu" "F.Mask" "F.Paste")
			(net "M_G_CPU1_SB_DQS_DN<9>")
		)
		(pad "95" smd rect
			(at -2.050034 21.67509 270)
			(size 0.519938 1.4986)
			(layers "F.Cu" "F.Mask" "F.Paste")
			(net "GND")
		)
		(pad "96" smd rect
			(at -2.050034 22.524974 270)
			(size 0.519938 1.4986)
			(layers "F.Cu" "F.Mask" "F.Paste")
			(net "M_G_CPU1_SB_CB<0>")
		)
		(pad "97" smd rect
			(at -2.050034 23.375112 270)
			(size 0.519938 1.4986)
			(layers "F.Cu" "F.Mask" "F.Paste")
			(net "GND")
		)
		(pad "98" smd rect
			(at -2.050034 24.224996 270)
			(size 0.519938 1.4986)
			(layers "F.Cu" "F.Mask" "F.Paste")
			(net "M_G_CPU1_SB_CB<1>")
		)
		(pad "99" smd rect
			(at -2.050034 25.07488 270)
			(size 0.519938 1.4986)
			(layers "F.Cu" "F.Mask" "F.Paste")
			(net "GND")
		)
		(pad "100" smd rect
			(at -2.050034 25.925018 270)
			(size 0.519938 1.4986)
			(layers "F.Cu" "F.Mask" "F.Paste")
			(net "M_G_CPU1_SB_DQ<0>")
		)
		(pad "101" smd rect
			(at -2.050034 26.774902 270)
			(size 0.519938 1.4986)
			(layers "F.Cu" "F.Mask" "F.Paste")
			(net "GND")
		)
		(pad "102" smd rect
			(at -2.050034 27.62504 270)
			(size 0.519938 1.4986)
			(layers "F.Cu" "F.Mask" "F.Paste")
			(net "M_G_CPU1_SB_DQ<1>")
		)
		(pad "103" smd rect
			(at -2.050034 28.474924 270)
			(size 0.519938 1.4986)
			(layers "F.Cu" "F.Mask" "F.Paste")
			(net "GND")
		)
		(pad "104" smd rect
			(at -2.050034 29.325062 270)
			(size 0.519938 1.4986)
			(layers "F.Cu" "F.Mask" "F.Paste")
			(net "M_G_CPU1_SB_DQS_DP<0>")
		)
		(pad "105" smd rect
			(at -2.050034 30.174946 270)
			(size 0.519938 1.4986)
			(layers "F.Cu" "F.Mask" "F.Paste")
			(net "M_G_CPU1_SB_DQS_DN<0>")
		)
		(pad "106" smd rect
			(at -2.050034 31.025084 270)
			(size 0.519938 1.4986)
			(layers "F.Cu" "F.Mask" "F.Paste")
			(net "GND")
		)
		(pad "107" smd rect
			(at -2.050034 31.874968 270)
			(size 0.519938 1.4986)
			(layers "F.Cu" "F.Mask" "F.Paste")
			(net "M_G_CPU1_SB_DQ<4>")
		)
		(pad "108" smd rect
			(at -2.050034 32.725106 270)
			(size 0.519938 1.4986)
			(layers "F.Cu" "F.Mask" "F.Paste")
			(net "GND")
		)
		(pad "109" smd rect
			(at -2.050034 33.57499 270)
			(size 0.519938 1.4986)
			(layers "F.Cu" "F.Mask" "F.Paste")
			(net "M_G_CPU1_SB_DQ<5>")
		)
		(pad "110" smd rect
			(at -2.050034 34.425128 270)
			(size 0.519938 1.4986)
			(layers "F.Cu" "F.Mask" "F.Paste")
			(net "GND")
		)
		(pad "111" smd rect
			(at -2.050034 35.275012 270)
			(size 0.519938 1.4986)
			(layers "F.Cu" "F.Mask" "F.Paste")
			(net "M_G_CPU1_SB_DQ<8>")
		)
		(pad "112" smd rect
			(at -2.050034 36.124896 270)
			(size 0.519938 1.4986)
			(layers "F.Cu" "F.Mask" "F.Paste")
			(net "GND")
		)
		(pad "113" smd rect
			(at -2.050034 36.975034 270)
			(size 0.519938 1.4986)
			(layers "F.Cu" "F.Mask" "F.Paste")
			(net "M_G_CPU1_SB_DQ<9>")
		)
		(pad "114" smd rect
			(at -2.050034 37.824918 270)
			(size 0.519938 1.4986)
			(layers "F.Cu" "F.Mask" "F.Paste")
			(net "GND")
		)
		(pad "115" smd rect
			(at -2.050034 38.675056 270)
			(size 0.519938 1.4986)
			(layers "F.Cu" "F.Mask" "F.Paste")
			(net "M_G_CPU1_SB_DQS_DP<1>")
		)
		(pad "116" smd rect
			(at -2.050034 39.52494 270)
			(size 0.519938 1.4986)
			(layers "F.Cu" "F.Mask" "F.Paste")
			(net "M_G_CPU1_SB_DQS_DN<1>")
		)
		(pad "117" smd rect
			(at -2.050034 40.375078 270)
			(size 0.519938 1.4986)
			(layers "F.Cu" "F.Mask" "F.Paste")
			(net "GND")
		)
		(pad "118" smd rect
			(at -2.050034 41.224962 270)
			(size 0.519938 1.4986)
			(layers "F.Cu" "F.Mask" "F.Paste")
			(net "M_G_CPU1_SB_DQ<12>")
		)
		(pad "119" smd rect
			(at -2.050034 42.0751 270)
			(size 0.519938 1.4986)
			(layers "F.Cu" "F.Mask" "F.Paste")
			(net "GND")
		)
		(pad "120" smd rect
			(at -2.050034 42.924984 270)
			(size 0.519938 1.4986)
			(layers "F.Cu" "F.Mask" "F.Paste")
			(net "M_G_CPU1_SB_DQ<13>")
		)
		(pad "121" smd rect
			(at -2.050034 43.775122 270)
			(size 0.519938 1.4986)
			(layers "F.Cu" "F.Mask" "F.Paste")
			(net "GND")
		)
		(pad "122" smd rect
			(at -2.050034 44.625006 270)
			(size 0.519938 1.4986)
			(layers "F.Cu" "F.Mask" "F.Paste")
			(net "M_G_CPU1_SB_DQ<16>")
		)
		(pad "123" smd rect
			(at -2.050034 45.47489 270)
			(size 0.519938 1.4986)
			(layers "F.Cu" "F.Mask" "F.Paste")
			(net "GND")
		)
		(pad "124" smd rect
			(at -2.050034 46.325028 270)
			(size 0.519938 1.4986)
			(layers "F.Cu" "F.Mask" "F.Paste")
			(net "M_G_CPU1_SB_DQ<17>")
		)
		(pad "125" smd rect
			(at -2.050034 47.174912 270)
			(size 0.519938 1.4986)
			(layers "F.Cu" "F.Mask" "F.Paste")
			(net "GND")
		)
		(pad "126" smd rect
			(at -2.050034 48.02505 270)
			(size 0.519938 1.4986)
			(layers "F.Cu" "F.Mask" "F.Paste")
			(net "M_G_CPU1_SB_DQS_DP<2>")
		)
		(pad "127" smd rect
			(at -2.050034 48.874934 270)
			(size 0.519938 1.4986)
			(layers "F.Cu" "F.Mask" "F.Paste")
			(net "M_G_CPU1_SB_DQS_DN<2>")
		)
		(pad "128" smd rect
			(at -2.050034 49.725072 270)
			(size 0.519938 1.4986)
			(layers "F.Cu" "F.Mask" "F.Paste")
			(net "GND")
		)
		(pad "129" smd rect
			(at -2.050034 50.574956 270)
			(size 0.519938 1.4986)
			(layers "F.Cu" "F.Mask" "F.Paste")
			(net "M_G_CPU1_SB_DQ<20>")
		)
		(pad "130" smd rect
			(at -2.050034 51.425094 270)
			(size 0.519938 1.4986)
			(layers "F.Cu" "F.Mask" "F.Paste")
			(net "GND")
		)
		(pad "131" smd rect
			(at -2.050034 52.274978 270)
			(size 0.519938 1.4986)
			(layers "F.Cu" "F.Mask" "F.Paste")
			(net "M_G_CPU1_SB_DQ<21>")
		)
		(pad "132" smd rect
			(at -2.050034 53.125116 270)
			(size 0.519938 1.4986)
			(layers "F.Cu" "F.Mask" "F.Paste")
			(net "GND")
		)
		(pad "133" smd rect
			(at -2.050034 53.975 270)
			(size 0.519938 1.4986)
			(layers "F.Cu" "F.Mask" "F.Paste")
			(net "M_G_CPU1_SB_DQ<24>")
		)
		(pad "134" smd rect
			(at -2.050034 54.824884 270)
			(size 0.519938 1.4986)
			(layers "F.Cu" "F.Mask" "F.Paste")
			(net "GND")
		)
		(pad "135" smd rect
			(at -2.050034 55.675022 270)
			(size 0.519938 1.4986)
			(layers "F.Cu" "F.Mask" "F.Paste")
			(net "M_G_CPU1_SB_DQ<25>")
		)
		(pad "136" smd rect
			(at -2.050034 56.524906 270)
			(size 0.519938 1.4986)
			(layers "F.Cu" "F.Mask" "F.Paste")
			(net "GND")
		)
		(pad "137" smd rect
			(at -2.050034 57.375044 270)
			(size 0.519938 1.4986)
			(layers "F.Cu" "F.Mask" "F.Paste")
			(net "M_G_CPU1_SB_DQS_DP<3>")
		)
	)
)
